# BASEBOARD_FAB2 (Tioga Pass) — schematic netlist excerpt (pin names and nets, part order shuffled) for the footprints in the layout excerpt that follows; sources: Cadence DE-HDL packaged netlist, KiCad conversion of Wiwynn_Tioga_Pass_MB.brd

EU8A1  PXE1110B  IC  pkg QFN  page 235
  DNC(0)  = NC
  DNC(1)  = NC
  BPWM1  = VR_P1V05_PCH_STBY_PWM1
  DNC(2)  = NC
  APWM1  = VR_PVNN_PCH_PWM1
  SDA  = SMB_VR_STBY_LVC3_SDA
  SCL  = SMB_VR_STBY_LVC3_SCL
  RESET_N  = NC
  AVRRDY  = PWRGD_PVNN_PCH_R
  AVREN  = VR_PVNN_PCH_VREN
  VRHOT_N  = IRQ_PVNN_PCH_VRHOT_N
  PINALRT_N  = PU_PVNN_PCH_PINALRT_N
  MP0  = VID_PCH_CORE_PVNN_AUX_VID_0
  MP1  = VID_PCH_CORE_PVNN_AUX_VID_1
  VCLK  = PU_PVNN_PCH_VCLK
  VDIO  = PU_PVNN_PCH_VDIO
  VALRT_N  = NC
  MP2  = NC
  AVSEN  = VR_PVNN_PCH_AVSP
  AVREF  = VSENSE_PVNN_PCH_STBY_AVSN
  AIREF1  = VR_PVNN_PCH_AIREF1
  AISEN1  = ISENSE_PVNN_PCH_PH1_IMON
  GND(1)  = GND
  DNC(3)  = NC
  BIREF1  = VR_P1V05_PCH_BIREF1
  BISEN1  = ISENSE_P1V05_PCH_STBY_PH1_IMON
  GND(0)  = GND
  DNC(4)  = NC
  BVSEN  = VR_P1V05_PCH_STBY_AVSP
  BVREF  = VSENSE_P1V05_PCH_STBY_AVSN
  MP3  = NC
  MP4  = PU_VR_PVNN_PCH_FAULT1
  XADDR2  = VR_PVNN_PCH_XADDR2
  BTSEN  = A_TSENSE_P1V05_PCH_STBY_TMON
  ATSEN  = A_TSENSE_PVNN_PCH_TMON
  XADDR1  = VR_PVNN_PCH_XADDR1
  VINSEN  = VR_PVNN_PCH_VINSEN
  IINSEN  = NC
  VDD  = VR_PVNN_PCH_VDD
  VD12  = VR_PVNN_P1V05_PCH_VD12
  THPAD  = GND

(kicad_pcb
	(version 20260206)
	(generator "pcbnew")
	(generator_version "10.0")
	(general
		(thickness 1.6)
		(legacy_teardrops no)
	)
	(paper "A4")
	(title_block
		(title "Wiwynn_Tioga_Pass_MB.brd")
		(comment 1 "Tioga Pass / footprint 1719 of 4770 (EU8A1), pads 18-34 of 41")
	)
	(layers
		(0 "F.Cu" signal "TOP")
		(4 "In1.Cu" signal "L2GND")
		(6 "In2.Cu" signal "L3")
		(8 "In3.Cu" signal "L4GND")
		(10 "In4.Cu" signal "L5")
		(12 "In5.Cu" signal "L6GND")
		(14 "In6.Cu" signal "L7VCC")
		(16 "In7.Cu" signal "L8VCC")
		(18 "In8.Cu" signal "L9GND")
		(20 "In9.Cu" signal "L10")
		(22 "In10.Cu" signal "L11GND")
		(24 "In11.Cu" signal "L12")
		(26 "In12.Cu" signal "L13GND")
		(2 "B.Cu" signal "BOTTOM")
		(9 "F.Adhes" user "F.Adhesive")
		(11 "B.Adhes" user "B.Adhesive")
		(13 "F.Paste" user "Package Geometry/Pastemask Top")
		(15 "B.Paste" user "Package Geometry/Pastemask Bottom")
		(5 "F.SilkS" user "Ref Des/Silkscreen Top")
		(7 "B.SilkS" user "Ref Des/Silkscreen Bottom")
		(1 "F.Mask" user "Board Geometry/Soldermask Top")
		(3 "B.Mask" user "Board Geometry/Soldermask Bottom")
		(17 "Dwgs.User" user "User.Drawings")
		(19 "Cmts.User" user "User.Comments")
		(21 "Eco1.User" user "User.Eco1")
		(23 "Eco2.User" user "User.Eco2")
		(25 "Edge.Cuts" user "Board Geometry/Outline")
		(27 "Margin" user)
		(31 "F.CrtYd" user "Package Geometry/Place Bound Top")
		(29 "B.CrtYd" user "Package Geometry/Place Bound Bottom")
		(35 "F.Fab" user "Ref Des/Assembly Top")
		(33 "B.Fab" user "Ref Des/Assembly Bottom")
	)
	(footprint ""
		(layer "F.Cu")
		(at 395.7828 -153.797 90)
		(property "Reference" "EU8A1"
			(at 3.40233 -2.7178 0)
			(unlocked yes)
			(layer "F.SilkS")
			(effects
				(font
					(size 0.7874 0.5842)
					(thickness 0.1524)
				)
				(justify left)
			)
		)
		(property "Value" ""
			(at 0 0 90)
			(layer "F.Fab")
			(effects
				(font
					(size 1.27 1.27)
				)
			)
		)
		(duplicate_pad_numbers_are_jumpers no)
		(pad "18" smd custom
			(at 0.999998 2.4511 90)
			(size 0.0508 0.0508)
			(layers "F.Cu" "F.Mask" "F.Paste")
			(net "Net_298")
			(options
				(clearance outline)
				(anchor circle)
			)
			(primitives
				(gr_poly
					(pts
						(arc
							(start -0.1016 -0.254)
							(mid 0 -0.3556)
							(end 0.1016 -0.254)
						)
						(xy 0.1016 0.3556) (xy -0.1016 0.3556)
					)
					(width 0)
					(fill yes)
				)
			)
		)
		(pad "19" smd custom
			(at 1.400048 2.4511 90)
			(size 0.0508 0.0508)
			(layers "F.Cu" "F.Mask" "F.Paste")
			(net "VR_PVNN_PCH_AVSP")
			(options
				(clearance outline)
				(anchor circle)
			)
			(primitives
				(gr_poly
					(pts
						(arc
							(start -0.1016 -0.254)
							(mid 0 -0.3556)
							(end 0.1016 -0.254)
						)
						(xy 0.1016 0.3556) (xy -0.1016 0.3556)
					)
					(width 0)
					(fill yes)
				)
			)
		)
		(pad "20" smd custom
			(at 1.800098 2.4511 90)
			(size 0.0508 0.0508)
			(layers "F.Cu" "F.Mask" "F.Paste")
			(net "VSENSE_PVNN_PCH_STBY_AVSN")
			(options
				(clearance outline)
				(anchor circle)
			)
			(primitives
				(gr_poly
					(pts
						(arc
							(start -0.1016 -0.254)
							(mid 0 -0.3556)
							(end 0.1016 -0.254)
						)
						(xy 0.1016 0.3556) (xy -0.1016 0.3556)
					)
					(width 0)
					(fill yes)
				)
			)
		)
		(pad "21" smd custom
			(at 2.4511 1.800098 90)
			(size 0.0508 0.0508)
			(layers "F.Cu" "F.Mask" "F.Paste")
			(net "VR_PVNN_PCH_AIREF1")
			(options
				(clearance outline)
				(anchor circle)
			)
			(primitives
				(gr_poly
					(pts
						(arc
							(start -0.254 0.1016)
							(mid -0.3556 0)
							(end -0.254 -0.1016)
						)
						(xy 0.3556 -0.1016) (xy 0.3556 0.1016)
					)
					(width 0)
					(fill yes)
				)
			)
		)
		(pad "22" smd custom
			(at 2.4511 1.400048 90)
			(size 0.0508 0.0508)
			(layers "F.Cu" "F.Mask" "F.Paste")
			(net "ISENSE_PVNN_PCH_PH1_IMON")
			(options
				(clearance outline)
				(anchor circle)
			)
			(primitives
				(gr_poly
					(pts
						(arc
							(start -0.254 0.1016)
							(mid -0.3556 0)
							(end -0.254 -0.1016)
						)
						(xy 0.3556 -0.1016) (xy 0.3556 0.1016)
					)
					(width 0)
					(fill yes)
				)
			)
		)
		(pad "23" smd custom
			(at 2.4511 0.999998 90)
			(size 0.0508 0.0508)
			(layers "F.Cu" "F.Mask" "F.Paste")
			(net "GND")
			(options
				(clearance outline)
				(anchor circle)
			)
			(primitives
				(gr_poly
					(pts
						(arc
							(start -0.254 0.1016)
							(mid -0.3556 0)
							(end -0.254 -0.1016)
						)
						(xy 0.3556 -0.1016) (xy 0.3556 0.1016)
					)
					(width 0)
					(fill yes)
				)
			)
		)
		(pad "24" smd custom
			(at 2.4511 0.599948 90)
			(size 0.0508 0.0508)
			(layers "F.Cu" "F.Mask" "F.Paste")
			(net "Net_354")
			(options
				(clearance outline)
				(anchor circle)
			)
			(primitives
				(gr_poly
					(pts
						(arc
							(start -0.254 0.1016)
							(mid -0.3556 0)
							(end -0.254 -0.1016)
						)
						(xy 0.3556 -0.1016) (xy 0.3556 0.1016)
					)
					(width 0)
					(fill yes)
				)
			)
		)
		(pad "25" smd custom
			(at 2.4511 0.199898 90)
			(size 0.0508 0.0508)
			(layers "F.Cu" "F.Mask" "F.Paste")
			(net "VR_P1V05_PCH_BIREF1")
			(options
				(clearance outline)
				(anchor circle)
			)
			(primitives
				(gr_poly
					(pts
						(arc
							(start -0.254 0.1016)
							(mid -0.3556 0)
							(end -0.254 -0.1016)
						)
						(xy 0.3556 -0.1016) (xy 0.3556 0.1016)
					)
					(width 0)
					(fill yes)
				)
			)
		)
		(pad "26" smd custom
			(at 2.4511 -0.199898 90)
			(size 0.0508 0.0508)
			(layers "F.Cu" "F.Mask" "F.Paste")
			(net "ISENSE_P1V05_PCH_STBY_PH1_IMON")
			(options
				(clearance outline)
				(anchor circle)
			)
			(primitives
				(gr_poly
					(pts
						(arc
							(start -0.254 0.1016)
							(mid -0.3556 0)
							(end -0.254 -0.1016)
						)
						(xy 0.3556 -0.1016) (xy 0.3556 0.1016)
					)
					(width 0)
					(fill yes)
				)
			)
		)
		(pad "27" smd custom
			(at 2.4511 -0.599948 90)
			(size 0.0508 0.0508)
			(layers "F.Cu" "F.Mask" "F.Paste")
			(net "GND")
			(options
				(clearance outline)
				(anchor circle)
			)
			(primitives
				(gr_poly
					(pts
						(arc
							(start -0.254 0.1016)
							(mid -0.3556 0)
							(end -0.254 -0.1016)
						)
						(xy 0.3556 -0.1016) (xy 0.3556 0.1016)
					)
					(width 0)
					(fill yes)
				)
			)
		)
		(pad "28" smd custom
			(at 2.4511 -0.999998 90)
			(size 0.0508 0.0508)
			(layers "F.Cu" "F.Mask" "F.Paste")
			(net "Net_355")
			(options
				(clearance outline)
				(anchor circle)
			)
			(primitives
				(gr_poly
					(pts
						(arc
							(start -0.254 0.1016)
							(mid -0.3556 0)
							(end -0.254 -0.1016)
						)
						(xy 0.3556 -0.1016) (xy 0.3556 0.1016)
					)
					(width 0)
					(fill yes)
				)
			)
		)
		(pad "29" smd custom
			(at 2.4511 -1.400048 90)
			(size 0.0508 0.0508)
			(layers "F.Cu" "F.Mask" "F.Paste")
			(net "VR_P1V05_PCH_STBY_AVSP")
			(options
				(clearance outline)
				(anchor circle)
			)
			(primitives
				(gr_poly
					(pts
						(arc
							(start -0.254 0.1016)
							(mid -0.3556 0)
							(end -0.254 -0.1016)
						)
						(xy 0.3556 -0.1016) (xy 0.3556 0.1016)
					)
					(width 0)
					(fill yes)
				)
			)
		)
		(pad "30" smd custom
			(at 2.4511 -1.800098 90)
			(size 0.0508 0.0508)
			(layers "F.Cu" "F.Mask" "F.Paste")
			(net "VSENSE_P1V05_PCH_STBY_AVSN")
			(options
				(clearance outline)
				(anchor circle)
			)
			(primitives
				(gr_poly
					(pts
						(arc
							(start -0.254 0.1016)
							(mid -0.3556 0)
							(end -0.254 -0.1016)
						)
						(xy 0.3556 -0.1016) (xy 0.3556 0.1016)
					)
					(width 0)
					(fill yes)
				)
			)
		)
		(pad "31" smd custom
			(at 1.800098 -2.4511 90)
			(size 0.0508 0.0508)
			(layers "F.Cu" "F.Mask" "F.Paste")
			(net "Net_299")
			(options
				(clearance outline)
				(anchor circle)
			)
			(primitives
				(gr_poly
					(pts
						(arc
							(start 0.1016 0.254)
							(mid 0 0.3556)
							(end -0.1016 0.254)
						)
						(xy -0.1016 -0.3556) (xy 0.1016 -0.3556)
					)
					(width 0)
					(fill yes)
				)
			)
		)
		(pad "32" smd custom
			(at 1.400048 -2.4511 90)
			(size 0.0508 0.0508)
			(layers "F.Cu" "F.Mask" "F.Paste")
			(net "PU_VR_PVNN_PCH_FAULT1")
			(options
				(clearance outline)
				(anchor circle)
			)
			(primitives
				(gr_poly
					(pts
						(arc
							(start 0.1016 0.254)
							(mid 0 0.3556)
							(end -0.1016 0.254)
						)
						(xy -0.1016 -0.3556) (xy 0.1016 -0.3556)
					)
					(width 0)
					(fill yes)
				)
			)
		)
		(pad "33" smd custom
			(at 0.999998 -2.4511 90)
			(size 0.0508 0.0508)
			(layers "F.Cu" "F.Mask" "F.Paste")
			(net "VR_PVNN_PCH_XADDR2")
			(options
				(clearance outline)
				(anchor circle)
			)
			(primitives
				(gr_poly
					(pts
						(arc
							(start 0.1016 0.254)
							(mid 0 0.3556)
							(end -0.1016 0.254)
						)
						(xy -0.1016 -0.3556) (xy 0.1016 -0.3556)
					)
					(width 0)
					(fill yes)
				)
			)
		)
		(pad "34" smd custom
			(at 0.599948 -2.4511 90)
			(size 0.0508 0.0508)
			(layers "F.Cu" "F.Mask" "F.Paste")
			(net "A_TSENSE_P1V05_PCH_STBY_TMON")
			(options
				(clearance outline)
				(anchor circle)
			)
			(primitives
				(gr_poly
					(pts
						(arc
							(start 0.1016 0.254)
							(mid 0 0.3556)
							(end -0.1016 0.254)
						)
						(xy -0.1016 -0.3556) (xy 0.1016 -0.3556)
					)
					(width 0)
					(fill yes)
				)
			)
		)
	)
)
